(kicad_pcb
	(version 20260206)
	(generator "pcbnew")
	(generator_version "10.0")
	(general
		(thickness 1.6)
		(legacy_teardrops no)
	)
	(paper "A4")
	(title_block
		(title "dpb — 14545-sa.0730WZS0815.brd")
		(comment 1 "Honey Badger (Wiwynn) / footprints 48-55 of 1066")
	)
	(layers
		(0 "F.Cu" signal "TOP")
		(4 "In1.Cu" signal "L2GND")
		(6 "In2.Cu" signal "L3")
		(8 "In3.Cu" signal "L4VCC")
		(10 "In4.Cu" signal "L5VCC")
		(12 "In5.Cu" signal "L6")
		(14 "In6.Cu" signal "L7GND")
		(2 "B.Cu" signal "BOTTOM")
		(9 "F.Adhes" user "F.Adhesive")
		(11 "B.Adhes" user "B.Adhesive")
		(13 "F.Paste" user "Package Geometry/Pastemask Top")
		(15 "B.Paste" user "Package Geometry/Pastemask Bottom")
		(5 "F.SilkS" user "Ref Des/Silkscreen Top")
		(7 "B.SilkS" user "Ref Des/Silkscreen Bottom")
		(1 "F.Mask" user "Board Geometry/Soldermask Top")
		(3 "B.Mask" user "Board Geometry/Soldermask Bottom")
		(17 "Dwgs.User" user "User.Drawings")
		(19 "Cmts.User" user "User.Comments")
		(21 "Eco1.User" user "User.Eco1")
		(23 "Eco2.User" user "User.Eco2")
		(25 "Edge.Cuts" user "Board Geometry/Outline")
		(27 "Margin" user)
		(31 "F.CrtYd" user "Package Geometry/Place Bound Top")
		(29 "B.CrtYd" user "Package Geometry/Place Bound Bottom")
		(35 "F.Fab" user "Ref Des/Assembly Top")
		(33 "B.Fab" user "Ref Des/Assembly Bottom")
	)
	(footprint ""
		(layer "F.Cu")
		(at 68.999608 -67.999864)
		(property "Reference" "H9"
			(at 0 0 0)
			(layer "F.SilkS")
			(hide yes)
			(effects
				(font
					(size 1.27 1.27)
				)
			)
		)
		(property "Value" "HOLE315R140"
			(at 0 -7.5692 0)
			(unlocked yes)
			(layer "F.Fab")
			(hide yes)
			(effects
				(font
					(size 1.016 1.016)
					(thickness 0.1524)
				)
			)
		)
		(property "Device Type" "HOLE315R140"
			(at 0 -9.0932 0)
			(unlocked yes)
			(layer "F.Fab")
			(hide yes)
			(effects
				(font
					(size 1.016 1.016)
					(thickness 0.1524)
				)
			)
		)
		(duplicate_pad_numbers_are_jumpers no)
		(fp_poly
			(pts
				(arc
					(start 4.3053 0)
					(mid -4.3053 0)
					(end 4.3053 0)
				)
			)
			(stroke
				(width 0)
				(type default)
			)
			(fill no)
			(layer "F.CrtYd")
		)
		(fp_poly
			(pts
				(arc
					(start 4.3053 0)
					(mid -4.3053 0)
					(end 4.3053 0)
				)
			)
			(stroke
				(width 0)
				(type default)
			)
			(fill no)
			(layer "F.Fab")
		)
		(pad "1" thru_hole circle
			(at 0.00127 0.00127)
			(size 8.001 8.001)
			(drill 3.556)
			(layers "*.Cu" "*.Mask")
			(remove_unused_layers no)
			(net "GND")
			(clearance -1.7145)
			(thermal_gap 0.3048)
			(padstack
				(mode front_inner_back)
				(layer "Inner"
					(shape circle)
					(size 3.9624 3.9624)
					(clearance 0.3048)
				)
				(layer "B.Cu"
					(shape circle)
					(size 8.001 8.001)
					(clearance -1.7145)
				)
			)
		)
	)
	(footprint ""
		(layer "F.Cu")
		(at 234.568746 -11.3157)
		(property "Reference" "PL1"
			(at 0 0 0)
			(layer "F.SilkS")
			(hide yes)
			(effects
				(font
					(size 1.27 1.27)
				)
			)
		)
		(property "Value" "BLM41PG600-GP"
			(at -3.690874 -7.441184 0)
			(unlocked yes)
			(layer "F.Fab")
			(hide yes)
			(effects
				(font
					(size 1.016 1.016)
					(thickness 0.1524)
				)
			)
		)
		(property "Device Type" "L451616H71"
			(at -3.690874 -5.917184 0)
			(unlocked yes)
			(layer "F.Fab")
			(hide yes)
			(effects
				(font
					(size 1.016 1.016)
					(thickness 0.1524)
				)
			)
		)
		(duplicate_pad_numbers_are_jumpers no)
		(fp_line
			(start -2.8702 -1.2954)
			(end -2.8702 1.2954)
			(stroke
				(width 0.1524)
				(type default)
			)
			(layer "F.SilkS")
		)
		(fp_line
			(start -2.8702 -1.2954)
			(end -2.8702 1.2954)
			(stroke
				(width 0.1524)
				(type default)
			)
			(layer "F.SilkS")
		)
		(fp_line
			(start -2.8702 1.2954)
			(end 2.8702 1.2954)
			(stroke
				(width 0.1524)
				(type default)
			)
			(layer "F.SilkS")
		)
		(fp_line
			(start -2.8702 1.2954)
			(end 2.8702 1.2954)
			(stroke
				(width 0.1524)
				(type default)
			)
			(layer "F.SilkS")
		)
		(fp_line
			(start 2.8702 -1.2954)
			(end -2.8702 -1.2954)
			(stroke
				(width 0.1524)
				(type default)
			)
			(layer "F.SilkS")
		)
		(fp_line
			(start 2.8702 -1.2954)
			(end -2.8702 -1.2954)
			(stroke
				(width 0.1524)
				(type default)
			)
			(layer "F.SilkS")
		)
		(fp_line
			(start 2.8702 1.2954)
			(end 2.8702 -1.2954)
			(stroke
				(width 0.1524)
				(type default)
			)
			(layer "F.SilkS")
		)
		(fp_line
			(start 2.8702 1.2954)
			(end 2.8702 -1.2954)
			(stroke
				(width 0.1524)
				(type default)
			)
			(layer "F.SilkS")
		)
		(fp_poly
			(pts
				(xy -2.8702 1.2954) (xy 2.8702 1.2954) (xy 2.8702 -1.2954) (xy -2.8702 -1.2954)
			)
			(stroke
				(width 0)
				(type default)
			)
			(fill no)
			(layer "F.CrtYd")
		)
		(fp_poly
			(pts
				(xy -2.8702 1.2954) (xy 2.8702 1.2954) (xy 2.8702 -1.2954) (xy -2.8702 -1.2954)
			)
			(stroke
				(width 0)
				(type default)
			)
			(fill no)
			(layer "F.Fab")
		)
		(pad "1" smd rect
			(at -1.9685 0)
			(size 1.3716 1.8796)
			(layers "F.Cu" "F.Mask" "F.Paste")
			(net "P12V")
		)
		(pad "2" smd rect
			(at 1.9685 0)
			(size 1.3716 1.8796)
			(layers "F.Cu" "F.Mask" "F.Paste")
			(net "P5VA_12VIN")
		)
	)
	(footprint ""
		(layer "F.Cu")
		(at 26.14803 -132.711952 90)
		(property "Reference" "C313"
			(at 0 0 90)
			(layer "F.SilkS")
			(hide yes)
			(effects
				(font
					(size 1.27 1.27)
				)
			)
		)
		(property "Value" "SCD01U50V2KX-1GP"
			(at 1.1811 -2.7051 90)
			(unlocked yes)
			(layer "F.Fab")
			(hide yes)
			(effects
				(font
					(size 1.016 1.016)
					(thickness 0.1524)
				)
			)
		)
		(property "Device Type" "C402H22"
			(at 1.1811 -4.2291 90)
			(unlocked yes)
			(layer "F.Fab")
			(hide yes)
			(effects
				(font
					(size 1.016 1.016)
					(thickness 0.1524)
				)
			)
		)
		(duplicate_pad_numbers_are_jumpers no)
		(fp_rect
			(start -0.4318 0.9525)
			(end 0.4318 -0.9525)
			(stroke
				(width 0)
				(type default)
			)
			(fill no)
			(layer "F.CrtYd")
		)
		(fp_rect
			(start -0.4318 0.9525)
			(end 0.4318 -0.9525)
			(stroke
				(width 0)
				(type default)
			)
			(fill no)
			(layer "F.Fab")
		)
		(pad "1" smd custom
			(at 0 -0.4445 90)
			(size 0.1524 0.1524)
			(layers "F.Cu" "F.Mask" "F.Paste")
			(net "SAS2X28_DRIVE_RX_P_B13")
			(options
				(clearance outline)
				(anchor circle)
			)
			(primitives
				(gr_poly
					(pts
						(arc
							(start 0.3048 -0.2032)
							(mid 0.275042 -0.275042)
							(end 0.2032 -0.3048)
						)
						(arc
							(start -0.2032 -0.3048)
							(mid -0.275042 -0.275042)
							(end -0.3048 -0.2032)
						)
						(arc
							(start -0.3048 0.2032)
							(mid -0.275042 0.275042)
							(end -0.2032 0.3048)
						)
						(arc
							(start 0.2032 0.3048)
							(mid 0.275042 0.275042)
							(end 0.3048 0.2032)
						)
					)
					(width 0)
					(fill yes)
				)
			)
		)
		(pad "2" smd custom
			(at 0 0.4445 90)
			(size 0.1524 0.1524)
			(layers "F.Cu" "F.Mask" "F.Paste")
			(net "SAS2X28_B_HDD13_RX_+")
			(options
				(clearance outline)
				(anchor circle)
			)
			(primitives
				(gr_poly
					(pts
						(arc
							(start 0.3048 -0.2032)
							(mid 0.275042 -0.275042)
							(end 0.2032 -0.3048)
						)
						(arc
							(start -0.2032 -0.3048)
							(mid -0.275042 -0.275042)
							(end -0.3048 -0.2032)
						)
						(arc
							(start -0.3048 0.2032)
							(mid -0.275042 0.275042)
							(end -0.2032 0.3048)
						)
						(arc
							(start 0.2032 0.3048)
							(mid 0.275042 0.275042)
							(end 0.3048 0.2032)
						)
					)
					(width 0)
					(fill yes)
				)
			)
		)
	)
	(footprint ""
		(layer "F.Cu")
		(at 76.453746 -15.522702)
		(property "Reference" "C331"
			(at 0 0 0)
			(layer "F.SilkS")
			(hide yes)
			(effects
				(font
					(size 1.27 1.27)
				)
			)
		)
		(property "Value" "SC10U16V6KX-2GP"
			(at -0.0762 -5.1308 0)
			(unlocked yes)
			(layer "F.Fab")
			(hide yes)
			(effects
				(font
					(size 1.016 1.016)
					(thickness 0.1524)
				)
			)
		)
		(property "Device Type" "C1206H71"
			(at -0.127 -6.6548 0)
			(unlocked yes)
			(layer "F.Fab")
			(hide yes)
			(effects
				(font
					(size 1.016 1.016)
					(thickness 0.1524)
				)
			)
		)
		(duplicate_pad_numbers_are_jumpers no)
		(fp_line
			(start -1.016 -2.2352)
			(end 1.016 -2.2352)
			(stroke
				(width 0.1524)
				(type default)
			)
			(layer "F.SilkS")
		)
		(fp_line
			(start -1.016 -0.8382)
			(end -1.016 -2.2352)
			(stroke
				(width 0.1524)
				(type default)
			)
			(layer "F.SilkS")
		)
		(fp_line
			(start -1.016 2.2352)
			(end -1.016 0.8382)
			(stroke
				(width 0.1524)
				(type default)
			)
			(layer "F.SilkS")
		)
		(fp_line
			(start 1.016 -2.2352)
			(end 1.016 -0.8382)
			(stroke
				(width 0.1524)
				(type default)
			)
			(layer "F.SilkS")
		)
		(fp_line
			(start 1.016 0.8382)
			(end 1.016 2.2352)
			(stroke
				(width 0.1524)
				(type default)
			)
			(layer "F.SilkS")
		)
		(fp_line
			(start 1.016 2.2352)
			(end -1.016 2.2352)
			(stroke
				(width 0.1524)
				(type default)
			)
			(layer "F.SilkS")
		)
		(fp_rect
			(start -1.0922 2.3114)
			(end 1.0922 -2.3114)
			(stroke
				(width 0)
				(type default)
			)
			(fill no)
			(layer "F.CrtYd")
		)
		(fp_poly
			(pts
				(xy 1.0922 -2.3114) (xy 1.0922 2.3114) (xy -1.0922 2.3114) (xy -1.0922 -2.3114)
			)
			(stroke
				(width 0)
				(type default)
			)
			(fill no)
			(layer "F.Fab")
		)
		(pad "1" smd rect
			(at 0 -1.397)
			(size 1.651 1.27)
			(layers "F.Cu" "F.Mask" "F.Paste")
			(net "P5V_HDD14")
		)
		(pad "2" smd rect
			(at 0 1.397)
			(size 1.651 1.27)
			(layers "F.Cu" "F.Mask" "F.Paste")
			(net "GND")
		)
	)
	(footprint ""
		(layer "F.Cu")
		(at 19.176746 -469.6587 -90)
		(property "Reference" "R244"
			(at 0 0 270)
			(layer "F.SilkS")
			(hide yes)
			(effects
				(font
					(size 1.27 1.27)
				)
			)
		)
		(property "Value" "0R2J-2-GP"
			(at 0.064008 -3.993896 270)
			(unlocked yes)
			(layer "F.Fab")
			(hide yes)
			(effects
				(font
					(size 1.016 1.016)
					(thickness 0.1524)
				)
			)
		)
		(property "Device Type" "R402H16"
			(at 0.064008 -5.517896 270)
			(unlocked yes)
			(layer "F.Fab")
			(hide yes)
			(effects
				(font
					(size 1.016 1.016)
					(thickness 0.1524)
				)
			)
		)
		(duplicate_pad_numbers_are_jumpers no)
		(fp_line
			(start -0.508 -0.9398)
			(end -0.508 0.9398)
			(stroke
				(width 0.1524)
				(type default)
			)
			(layer "F.SilkS")
		)
		(fp_line
			(start 0.508 -0.9398)
			(end -0.508 -0.9398)
			(stroke
				(width 0.1524)
				(type default)
			)
			(layer "F.SilkS")
		)
		(fp_rect
			(start -0.508 0.9398)
			(end 0.508 -0.9398)
			(stroke
				(width 0)
				(type default)
			)
			(fill no)
			(layer "F.CrtYd")
		)
		(fp_rect
			(start -0.508 0.9398)
			(end 0.508 -0.9398)
			(stroke
				(width 0)
				(type default)
			)
			(fill no)
			(layer "F.Fab")
		)
		(pad "1" smd custom
			(at 0 -0.4445 270)
			(size 0.1397 0.1397)
			(layers "F.Cu" "F.Mask" "F.Paste")
			(net "FLT_NET_HDD10")
			(options
				(clearance outline)
				(anchor circle)
			)
			(primitives
				(gr_poly
					(pts
						(arc
							(start -0.1778 -0.2794)
							(mid -0.249642 -0.249642)
							(end -0.2794 -0.1778)
						)
						(arc
							(start -0.2794 0.1778)
							(mid -0.249642 0.249642)
							(end -0.1778 0.2794)
						)
						(arc
							(start 0.1778 0.2794)
							(mid 0.249642 0.249642)
							(end 0.2794 0.1778)
						)
						(arc
							(start 0.2794 -0.1778)
							(mid 0.249642 -0.249642)
							(end 0.1778 -0.2794)
						)
					)
					(width 0)
					(fill yes)
				)
			)
		)
		(pad "2" smd custom
			(at 0 0.4445 270)
			(size 0.1397 0.1397)
			(layers "F.Cu" "F.Mask" "F.Paste")
			(net "FLT_HDD10_DRIVE")
			(options
				(clearance outline)
				(anchor circle)
			)
			(primitives
				(gr_poly
					(pts
						(arc
							(start -0.1778 -0.2794)
							(mid -0.249642 -0.249642)
							(end -0.2794 -0.1778)
						)
						(arc
							(start -0.2794 0.1778)
							(mid -0.249642 0.249642)
							(end -0.1778 0.2794)
						)
						(arc
							(start 0.1778 0.2794)
							(mid 0.249642 0.249642)
							(end 0.2794 0.1778)
						)
						(arc
							(start 0.2794 -0.1778)
							(mid 0.249642 -0.249642)
							(end 0.1778 -0.2794)
						)
					)
					(width 0)
					(fill yes)
				)
			)
		)
	)
	(footprint ""
		(layer "F.Cu")
		(at 191.092582 -287.373568 -90)
		(property "Reference" "R141"
			(at 0 0 270)
			(layer "F.SilkS")
			(hide yes)
			(effects
				(font
					(size 1.27 1.27)
				)
			)
		)
		(property "Value" "0R2J-2-GP"
			(at 0.064008 -3.993896 270)
			(unlocked yes)
			(layer "F.Fab")
			(hide yes)
			(effects
				(font
					(size 1.016 1.016)
					(thickness 0.1524)
				)
			)
		)
		(property "Device Type" "R402H16"
			(at 0.064008 -5.517896 270)
			(unlocked yes)
			(layer "F.Fab")
			(hide yes)
			(effects
				(font
					(size 1.016 1.016)
					(thickness 0.1524)
				)
			)
		)
		(duplicate_pad_numbers_are_jumpers no)
		(fp_line
			(start -0.508 -0.9398)
			(end -0.508 0.9398)
			(stroke
				(width 0.1524)
				(type default)
			)
			(layer "F.SilkS")
		)
		(fp_line
			(start 0.508 -0.9398)
			(end -0.508 -0.9398)
			(stroke
				(width 0.1524)
				(type default)
			)
			(layer "F.SilkS")
		)
		(fp_rect
			(start -0.508 0.9398)
			(end 0.508 -0.9398)
			(stroke
				(width 0)
				(type default)
			)
			(fill no)
			(layer "F.CrtYd")
		)
		(fp_rect
			(start -0.508 0.9398)
			(end 0.508 -0.9398)
			(stroke
				(width 0)
				(type default)
			)
			(fill no)
			(layer "F.Fab")
		)
		(pad "1" smd custom
			(at 0 -0.4445 270)
			(size 0.1397 0.1397)
			(layers "F.Cu" "F.Mask" "F.Paste")
			(net "DRIVE_PWR2")
			(options
				(clearance outline)
				(anchor circle)
			)
			(primitives
				(gr_poly
					(pts
						(arc
							(start -0.1778 -0.2794)
							(mid -0.249642 -0.249642)
							(end -0.2794 -0.1778)
						)
						(arc
							(start -0.2794 0.1778)
							(mid -0.249642 0.249642)
							(end -0.1778 0.2794)
						)
						(arc
							(start 0.1778 0.2794)
							(mid 0.249642 0.249642)
							(end 0.2794 0.1778)
						)
						(arc
							(start 0.2794 -0.1778)
							(mid 0.249642 -0.249642)
							(end 0.1778 -0.2794)
						)
					)
					(width 0)
					(fill yes)
				)
			)
		)
		(pad "2" smd custom
			(at 0 0.4445 270)
			(size 0.1397 0.1397)
			(layers "F.Cu" "F.Mask" "F.Paste")
			(net "SW_PWR_HDD2")
			(options
				(clearance outline)
				(anchor circle)
			)
			(primitives
				(gr_poly
					(pts
						(arc
							(start -0.1778 -0.2794)
							(mid -0.249642 -0.249642)
							(end -0.2794 -0.1778)
						)
						(arc
							(start -0.2794 0.1778)
							(mid -0.249642 0.249642)
							(end -0.1778 0.2794)
						)
						(arc
							(start 0.1778 0.2794)
							(mid 0.249642 0.249642)
							(end 0.2794 0.1778)
						)
						(arc
							(start 0.2794 -0.1778)
							(mid 0.249642 -0.249642)
							(end 0.1778 -0.2794)
						)
					)
					(width 0)
					(fill yes)
				)
			)
		)
	)
	(footprint ""
		(layer "F.Cu")
		(at 39.743634 -452.858886 90)
		(property "Reference" "R173"
			(at 0 0 90)
			(layer "F.SilkS")
			(hide yes)
			(effects
				(font
					(size 1.27 1.27)
				)
			)
		)
		(property "Value" "330R2F-GP"
			(at 0.064008 -3.993896 90)
			(unlocked yes)
			(layer "F.Fab")
			(hide yes)
			(effects
				(font
					(size 1.016 1.016)
					(thickness 0.1524)
				)
			)
		)
		(property "Device Type" "R402H16"
			(at 0.064008 -5.517896 90)
			(unlocked yes)
			(layer "F.Fab")
			(hide yes)
			(effects
				(font
					(size 1.016 1.016)
					(thickness 0.1524)
				)
			)
		)
		(duplicate_pad_numbers_are_jumpers no)
		(fp_line
			(start 0.508 -0.9398)
			(end -0.508 -0.9398)
			(stroke
				(width 0.1524)
				(type default)
			)
			(layer "F.SilkS")
		)
		(fp_line
			(start -0.508 -0.9398)
			(end -0.508 0.9398)
			(stroke
				(width 0.1524)
				(type default)
			)
			(layer "F.SilkS")
		)
		(fp_rect
			(start -0.508 0.9398)
			(end 0.508 -0.9398)
			(stroke
				(width 0)
				(type default)
			)
			(fill no)
			(layer "F.CrtYd")
		)
		(fp_rect
			(start -0.508 0.9398)
			(end 0.508 -0.9398)
			(stroke
				(width 0)
				(type default)
			)
			(fill no)
			(layer "F.Fab")
		)
		(pad "1" smd custom
			(at 0 -0.4445 90)
			(size 0.1397 0.1397)
			(layers "F.Cu" "F.Mask" "F.Paste")
			(net "P3V3_HDD5_LED")
			(options
				(clearance outline)
				(anchor circle)
			)
			(primitives
				(gr_poly
					(pts
						(arc
							(start -0.1778 -0.2794)
							(mid -0.249642 -0.249642)
							(end -0.2794 -0.1778)
						)
						(arc
							(start -0.2794 0.1778)
							(mid -0.249642 0.249642)
							(end -0.1778 0.2794)
						)
						(arc
							(start 0.1778 0.2794)
							(mid 0.249642 0.249642)
							(end 0.2794 0.1778)
						)
						(arc
							(start 0.2794 -0.1778)
							(mid 0.249642 -0.249642)
							(end 0.1778 -0.2794)
						)
					)
					(width 0)
					(fill yes)
				)
			)
		)
		(pad "2" smd custom
			(at 0 0.4445 90)
			(size 0.1397 0.1397)
			(layers "F.Cu" "F.Mask" "F.Paste")
			(net "FLT_HDD5")
			(options
				(clearance outline)
				(anchor circle)
			)
			(primitives
				(gr_poly
					(pts
						(arc
							(start -0.1778 -0.2794)
							(mid -0.249642 -0.249642)
							(end -0.2794 -0.1778)
						)
						(arc
							(start -0.2794 0.1778)
							(mid -0.249642 0.249642)
							(end -0.1778 0.2794)
						)
						(arc
							(start 0.1778 0.2794)
							(mid 0.249642 0.249642)
							(end 0.2794 0.1778)
						)
						(arc
							(start 0.2794 -0.1778)
							(mid 0.249642 -0.249642)
							(end 0.1778 -0.2794)
						)
					)
					(width 0)
					(fill yes)
				)
			)
		)
	)
	(footprint ""
		(layer "F.Cu")
		(at 215.979756 -488.597702 180)
		(property "Reference" "C107"
			(at 0 0 180)
			(layer "F.SilkS")
			(hide yes)
			(effects
				(font
					(size 1.27 1.27)
				)
			)
		)
		(property "Value" "SC10U16V6KX-2GP"
			(at -0.0762 -5.1308 180)
			(unlocked yes)
			(layer "F.Fab")
			(hide yes)
			(effects
				(font
					(size 1.016 1.016)
					(thickness 0.1524)
				)
			)
		)
		(property "Device Type" "C1206H71"
			(at -0.127 -6.6548 180)
			(unlocked yes)
			(layer "F.Fab")
			(hide yes)
			(effects
				(font
					(size 1.016 1.016)
					(thickness 0.1524)
				)
			)
		)
		(duplicate_pad_numbers_are_jumpers no)
		(fp_line
			(start 1.016 2.2352)
			(end -1.016 2.2352)
			(stroke
				(width 0.1524)
				(type default)
			)
			(layer "F.SilkS")
		)
		(fp_line
			(start 1.016 0.8382)
			(end 1.016 2.2352)
			(stroke
				(width 0.1524)
				(type default)
			)
			(layer "F.SilkS")
		)
		(fp_line
			(start 1.016 -2.2352)
			(end 1.016 -0.8382)
			(stroke
				(width 0.1524)
				(type default)
			)
			(layer "F.SilkS")
		)
		(fp_line
			(start -1.016 2.2352)
			(end -1.016 0.8382)
			(stroke
				(width 0.1524)
				(type default)
			)
			(layer "F.SilkS")
		)
		(fp_line
			(start -1.016 -0.8382)
			(end -1.016 -2.2352)
			(stroke
				(width 0.1524)
				(type default)
			)
			(layer "F.SilkS")
		)
		(fp_line
			(start -1.016 -2.2352)
			(end 1.016 -2.2352)
			(stroke
				(width 0.1524)
				(type default)
			)
			(layer "F.SilkS")
		)
		(fp_rect
			(start -1.0922 2.3114)
			(end 1.0922 -2.3114)
			(stroke
				(width 0)
				(type default)
			)
			(fill no)
			(layer "F.CrtYd")
		)
		(fp_poly
			(pts
				(xy 1.0922 -2.3114) (xy 1.0922 2.3114) (xy -1.0922 2.3114) (xy -1.0922 -2.3114)
			)
			(stroke
				(width 0)
				(type default)
			)
			(fill no)
			(layer "F.Fab")
		)
		(pad "1" smd rect
			(at 0 -1.397 180)
			(size 1.651 1.27)
			(layers "F.Cu" "F.Mask" "F.Paste")
			(net "P5V_HDD0")
		)
		(pad "2" smd rect
			(at 0 1.397 180)
			(size 1.651 1.27)
			(layers "F.Cu" "F.Mask" "F.Paste")
			(net "GND")
		)
	)
)
